# S9S_MB_2U (Grand Teton) — schematic netlist excerpt (pin names and nets, part order shuffled) for the footprints in the layout excerpt that follows; sources: Cadence DE-HDL packaged netlist, KiCad conversion of 03242023_DA0F0TMBIJ0_F0T_Motherboard_J_brd_V01_OCP.brd

PU292  RS31312R  IC  pkg QFN22_TH_3X5  page 193
  EN  = P12V_E1S_EN_0_R2
  LOADEN  = GND
  ENTM  = GND
  TIMER  = P12V_E1S_TIMER_0
  ISET  = P12V_E1S_ISET_0
  SS  = P12V_E1S_SS_0
  GND  = GND
  IMON  = P12V_E1S_IMON_0
  FLTB  = P12V_E1S_FLTB_0
  PG  = HP_LVC3_E1S_0_HSC_PWRGD
  OV  = P12V_E1S_OV_FB_0
  AVIN  = P12V_E1S_AVIN_PD_0
  VOUT_13  = P12V_E1S_0
  VOUT_14  = P12V_E1S_0
  VOUT_15  = P12V_E1S_0
  VOUT_16  = P12V_E1S_0
  VOUT_17  = P12V_E1S_0
  VOUT_18  = P12V_E1S_0
  VOUT_19  = P12V_E1S_0
  VOUT_20  = P12V_E1S_0
  VIN_21_22  = P12V_AUX
  VIN_23  = P12V_AUX
  VIN_24  = P12V_AUX
  VIN_25  = P12V_AUX
  VIN_26  = P12V_AUX

(kicad_pcb
	(version 20260206)
	(generator "pcbnew")
	(generator_version "10.0")
	(general
		(thickness 1.6)
		(legacy_teardrops no)
	)
	(paper "A4")
	(title_block
		(title "03242023_DA0F0TMBIJ0_F0T_Motherboard_J_brd_V01_OCP.brd")
		(comment 1 "Grand Teton / footprint 591 of 6105 (PU292), pads 1-25 of 25")
	)
	(layers
		(0 "F.Cu" signal "TOP")
		(4 "In1.Cu" signal "GND")
		(6 "In2.Cu" signal "IN1")
		(8 "In3.Cu" signal "GND1")
		(10 "In4.Cu" signal "IN2")
		(12 "In5.Cu" signal "GND2")
		(14 "In6.Cu" signal "IN3")
		(16 "In7.Cu" signal "GND3")
		(18 "In8.Cu" signal "VCC")
		(20 "In9.Cu" signal "VCC1")
		(22 "In10.Cu" signal "GND4")
		(24 "In11.Cu" signal "IN4")
		(26 "In12.Cu" signal "GND5")
		(28 "In13.Cu" signal "IN5")
		(30 "In14.Cu" signal "GND6")
		(32 "In15.Cu" signal "IN6")
		(34 "In16.Cu" signal "GND7")
		(2 "B.Cu" signal "BOTTOM")
		(9 "F.Adhes" user "F.Adhesive")
		(11 "B.Adhes" user "B.Adhesive")
		(13 "F.Paste" user "Package Geometry/Pastemask Top")
		(15 "B.Paste" user "Package Geometry/Pastemask Bottom")
		(5 "F.SilkS" user "Ref Des/Silkscreen Top")
		(7 "B.SilkS" user "Ref Des/Silkscreen Bottom")
		(1 "F.Mask" user "Board Geometry/Soldermask Top")
		(3 "B.Mask" user "Board Geometry/Soldermask Bottom")
		(17 "Dwgs.User" user "User.Drawings")
		(19 "Cmts.User" user "User.Comments")
		(21 "Eco1.User" user "User.Eco1")
		(23 "Eco2.User" user "User.Eco2")
		(25 "Edge.Cuts" user "Board Geometry/Outline")
		(27 "Margin" user)
		(31 "F.CrtYd" user "Package Geometry/Place Bound Top")
		(29 "B.CrtYd" user "Package Geometry/Place Bound Bottom")
		(35 "F.Fab" user "Ref Des/Assembly Top")
		(33 "B.Fab" user "Ref Des/Assembly Bottom")
	)
	(footprint ""
		(layer "F.Cu")
		(at 253.86157 -50.366422 180)
		(property "Reference" "PU292"
			(at 7.20217 0.018034 0)
			(unlocked yes)
			(layer "F.SilkS")
			(effects
				(font
					(size 0.7874 0.5842)
					(thickness 0.1524)
				)
				(justify left)
			)
		)
		(property "Value" ""
			(at 0 0 180)
			(layer "F.Fab")
			(effects
				(font
					(size 1.27 1.27)
				)
			)
		)
		(duplicate_pad_numbers_are_jumpers no)
		(pad "1" smd circle
			(at -1.374902 -1.999996 90)
			(size 0 0)
			(layers "F.Cu" "F.Mask" "F.Paste")
			(net "P12V_E1S_EN_0_R2")
		)
		(pad "2" smd rect
			(at -1.400048 -1.500124 90)
			(size 0.254 0.8128)
			(layers "F.Cu" "F.Mask" "F.Paste")
			(net "GND")
		)
		(pad "3" smd rect
			(at -1.400048 -0.999998 90)
			(size 0.254 0.8128)
			(layers "F.Cu" "F.Mask" "F.Paste")
			(net "GND")
		)
		(pad "4" smd rect
			(at -1.400048 -0.499872 90)
			(size 0.254 0.8128)
			(layers "F.Cu" "F.Mask" "F.Paste")
			(net "P12V_E1S_TIMER_0")
		)
		(pad "5" smd rect
			(at -1.400048 0 90)
			(size 0.254 0.8128)
			(layers "F.Cu" "F.Mask" "F.Paste")
			(net "P12V_E1S_ISET_0")
		)
		(pad "6" smd rect
			(at -1.400048 0.499872 90)
			(size 0.254 0.8128)
			(layers "F.Cu" "F.Mask" "F.Paste")
			(net "P12V_E1S_SS_0")
		)
		(pad "7" smd rect
			(at -1.400048 0.999998 90)
			(size 0.254 0.8128)
			(layers "F.Cu" "F.Mask" "F.Paste")
			(net "GND")
		)
		(pad "8" smd rect
			(at -1.400048 1.500124 90)
			(size 0.254 0.8128)
			(layers "F.Cu" "F.Mask" "F.Paste")
			(net "P12V_E1S_IMON_0")
		)
		(pad "9" smd rect
			(at -1.400048 1.999996 90)
			(size 0.254 0.8128)
			(layers "F.Cu" "F.Mask" "F.Paste")
			(net "P12V_E1S_FLTB_0")
		)
		(pad "10" smd rect
			(at -0.499872 2.400046 180)
			(size 0.254 0.8128)
			(layers "F.Cu" "F.Mask" "F.Paste")
			(net "HP_LVC3_E1S_0_HSC_PWRGD")
		)
		(pad "11" smd rect
			(at 0.499872 2.400046 180)
			(size 0.254 0.8128)
			(layers "F.Cu" "F.Mask" "F.Paste")
			(net "P12V_E1S_OV_FB_0")
		)
		(pad "12" smd rect
			(at 1.400048 1.999996 90)
			(size 0.254 0.8128)
			(layers "F.Cu" "F.Mask" "F.Paste")
			(net "P12V_E1S_AVIN_PD_0")
		)
		(pad "13" smd rect
			(at 1.400048 1.500124 90)
			(size 0.254 0.8128)
			(layers "F.Cu" "F.Mask" "F.Paste")
			(net "P12V_E1S_0")
		)
		(pad "14" smd rect
			(at 1.400048 0.999998 90)
			(size 0.254 0.8128)
			(layers "F.Cu" "F.Mask" "F.Paste")
			(net "P12V_E1S_0")
		)
		(pad "15" smd rect
			(at 1.400048 0.499872 90)
			(size 0.254 0.8128)
			(layers "F.Cu" "F.Mask" "F.Paste")
			(net "P12V_E1S_0")
		)
		(pad "16" smd rect
			(at 1.400048 0 90)
			(size 0.254 0.8128)
			(layers "F.Cu" "F.Mask" "F.Paste")
			(net "P12V_E1S_0")
		)
		(pad "17" smd rect
			(at 1.400048 -0.499872 90)
			(size 0.254 0.8128)
			(layers "F.Cu" "F.Mask" "F.Paste")
			(net "P12V_E1S_0")
		)
		(pad "18" smd rect
			(at 1.400048 -0.999998 90)
			(size 0.254 0.8128)
			(layers "F.Cu" "F.Mask" "F.Paste")
			(net "P12V_E1S_0")
		)
		(pad "19" smd rect
			(at 1.400048 -1.500124 90)
			(size 0.254 0.8128)
			(layers "F.Cu" "F.Mask" "F.Paste")
			(net "P12V_E1S_0")
		)
		(pad "20" smd rect
			(at 1.400048 -1.999996 90)
			(size 0.254 0.8128)
			(layers "F.Cu" "F.Mask" "F.Paste")
			(net "P12V_E1S_0")
		)
		(pad "21_22" smd circle
			(at 0.499872 -2.337562 90)
			(size 0 0)
			(layers "F.Cu" "F.Mask" "F.Paste")
			(net "P12V_AUX")
		)
		(pad "23" smd rect
			(at 0 -1.100074 90)
			(size 0.254 1.27)
			(layers "F.Cu" "F.Mask" "F.Paste")
			(net "P12V_AUX")
		)
		(pad "24" smd rect
			(at 0 -0.199898 90)
			(size 0.254 1.27)
			(layers "F.Cu" "F.Mask" "F.Paste")
			(net "P12V_AUX")
		)
		(pad "25" smd rect
			(at 0 0.700024 90)
			(size 0.254 1.27)
			(layers "F.Cu" "F.Mask" "F.Paste")
			(net "P12V_AUX")
		)
		(pad "26" smd rect
			(at 0 1.599946 90)
			(size 0.254 1.27)
			(layers "F.Cu" "F.Mask" "F.Paste")
			(net "P12V_AUX")
		)
	)
)
